# T6G (Grand Teton) — schematic netlist excerpt (pin names and nets, part order shuffled) for the footprints in the layout excerpt that follows; sources: Cadence DE-HDL packaged netlist, KiCad conversion of 04192023_DAF0TMB3IC0_F0TG_MB_C_brd_V02_OCP.brd

PU36  ISL99390FRZTR5935  ISL99390FRZ-TR5935 IC  pkg QFN21_6X5XB  page 219
  VOS  = PVDDCR_CPU1_P1_VOS4
  AGND  = GND
  VCC  = PVDDCR_CPU1_P1_VCC4
  PVCC  = PVDDCR_CPU1_P1_PVCC
  PGND1  = GND
  GL1  = NC_PVDDCR_CPU1_P1_GL1_4
  PGND2  = GND
  SW  = SW_PVDDCR_CPU1_P1_SW4
  VIN1  = SW_P12V_AUX_PVDDCR_CPU1_P1_FLT
  VIN2  = SW_P12V_AUX_PVDDCR_CPU1_P1_FLT
  DNC  = NC_PVDDCR_CPU1_P1_DNC4
  PHASE  = SW_PVDDCR_CPU1_P1_BOOTR4
  BOOT  = SW_PVDDCR_CPU1_P1_BOOT4
  PWM  = PVDDCR_CPU1_P1_PWM4
  EN  = PVDDCR_CPU1_P1_VCC4
  TOUT_FLT  = PVDDCR_CPU1_P1_TEMP0
  LSET  = PVDDCR_CPU1_P1_LSET4
  IOUT  = PVDDCR_CPU1_P1_IMON4
  REFIN  = PVDDCR_CPU1_P1_VCCS
  PGND3  = GND
  GL2  = NC_PVDDCR_CPU1_P1_GL2_4

(kicad_pcb
	(version 20260206)
	(generator "pcbnew")
	(generator_version "10.0")
	(general
		(thickness 1.6)
		(legacy_teardrops no)
	)
	(paper "A4")
	(title_block
		(title "04192023_DAF0TMB3IC0_F0TG_MB_C_brd_V02_OCP.brd")
		(comment 1 "Grand Teton / footprints 3184-3184 of 8354")
	)
	(layers
		(0 "F.Cu" signal "TOP")
		(4 "In1.Cu" signal "GND")
		(6 "In2.Cu" signal "IN1")
		(8 "In3.Cu" signal "GND1")
		(10 "In4.Cu" signal "IN2")
		(12 "In5.Cu" signal "GND2")
		(14 "In6.Cu" signal "IN3")
		(16 "In7.Cu" signal "GND3")
		(18 "In8.Cu" signal "VCC")
		(20 "In9.Cu" signal "VCC1")
		(22 "In10.Cu" signal "GND4")
		(24 "In11.Cu" signal "IN4")
		(26 "In12.Cu" signal "GND5")
		(28 "In13.Cu" signal "IN5")
		(30 "In14.Cu" signal "GND6")
		(32 "In15.Cu" signal "IN6")
		(34 "In16.Cu" signal "GND7")
		(2 "B.Cu" signal "BOTTOM")
		(9 "F.Adhes" user "F.Adhesive")
		(11 "B.Adhes" user "B.Adhesive")
		(13 "F.Paste" user "Package Geometry/Pastemask Top")
		(15 "B.Paste" user "Package Geometry/Pastemask Bottom")
		(5 "F.SilkS" user "Ref Des/Silkscreen Top")
		(7 "B.SilkS" user "Ref Des/Silkscreen Bottom")
		(1 "F.Mask" user "Board Geometry/Soldermask Top")
		(3 "B.Mask" user "Board Geometry/Soldermask Bottom")
		(17 "Dwgs.User" user "User.Drawings")
		(19 "Cmts.User" user "User.Comments")
		(21 "Eco1.User" user "User.Eco1")
		(23 "Eco2.User" user "User.Eco2")
		(25 "Edge.Cuts" user "Board Geometry/Outline")
		(27 "Margin" user)
		(31 "F.CrtYd" user "Package Geometry/Place Bound Top")
		(29 "B.CrtYd" user "Package Geometry/Place Bound Bottom")
		(35 "F.Fab" user "Ref Des/Assembly Top")
		(33 "B.Fab" user "Ref Des/Assembly Bottom")
	)
	(footprint ""
		(layer "F.Cu")
		(at 61.874654 -346.721176)
		(property "Reference" "PU36"
			(at -3.200654 -7.455154 0)
			(unlocked yes)
			(layer "F.SilkS")
			(effects
				(font
					(size 0.7874 0.5842)
					(thickness 0.1524)
				)
				(justify left)
			)
		)
		(property "Value" ""
			(at 0 0 0)
			(layer "F.Fab")
			(effects
				(font
					(size 1.27 1.27)
				)
			)
		)
		(duplicate_pad_numbers_are_jumpers no)
		(fp_line
			(start -2.500122 -2.999994)
			(end -2.24409 -2.999994)
			(stroke
				(width 0.1524)
				(type default)
			)
			(layer "F.SilkS")
		)
		(fp_line
			(start -2.500122 -2.529078)
			(end -2.500122 -2.999994)
			(stroke
				(width 0.1524)
				(type default)
			)
			(layer "F.SilkS")
		)
		(fp_line
			(start -2.500122 0.6604)
			(end -2.500122 0.229108)
			(stroke
				(width 0.1524)
				(type default)
			)
			(layer "F.SilkS")
		)
		(fp_line
			(start -2.500122 2.999994)
			(end -2.500122 2.339594)
			(stroke
				(width 0.1524)
				(type default)
			)
			(layer "F.SilkS")
		)
		(fp_line
			(start -2.2987 2.999994)
			(end -2.500122 2.999994)
			(stroke
				(width 0.1524)
				(type default)
			)
			(layer "F.SilkS")
		)
		(fp_line
			(start 2.31394 -2.999994)
			(end 2.500122 -2.999994)
			(stroke
				(width 0.1524)
				(type default)
			)
			(layer "F.SilkS")
		)
		(fp_line
			(start 2.500122 -2.999994)
			(end 2.500122 -2.44348)
			(stroke
				(width 0.1524)
				(type default)
			)
			(layer "F.SilkS")
		)
		(fp_line
			(start 2.500122 2.339594)
			(end 2.500122 2.999994)
			(stroke
				(width 0.1524)
				(type default)
			)
			(layer "F.SilkS")
		)
		(fp_line
			(start 2.500122 2.999994)
			(end 2.2987 2.999994)
			(stroke
				(width 0.1524)
				(type default)
			)
			(layer "F.SilkS")
		)
		(fp_poly
			(pts
				(xy -2.75336 -2.448306) (xy -3.426968 -2.672842) (xy -2.977896 -3.121914)
			)
			(stroke
				(width 0)
				(type default)
			)
			(fill yes)
			(layer "F.SilkS")
		)
		(fp_line
			(start -2.500122 -2.999994)
			(end 2.500122 -2.999994)
			(stroke
				(width 0.1)
				(type default)
			)
			(layer "F.Fab")
		)
		(fp_line
			(start -2.500122 2.999994)
			(end -2.500122 -2.999994)
			(stroke
				(width 0.1)
				(type default)
			)
			(layer "F.Fab")
		)
		(fp_line
			(start 2.500122 -2.999994)
			(end 2.500122 2.999994)
			(stroke
				(width 0.1)
				(type default)
			)
			(layer "F.Fab")
		)
		(fp_line
			(start 2.500122 2.999994)
			(end -2.500122 2.999994)
			(stroke
				(width 0.1)
				(type default)
			)
			(layer "F.Fab")
		)
		(fp_poly
			(pts
				(xy -4.218432 -2.783078) (xy -4.218432 -1.767078) (xy -3.202432 -2.275078)
			)
			(stroke
				(width 0)
				(type default)
			)
			(fill yes)
			(layer "F.Fab")
		)
		(pad "1" smd rect
			(at -2.400046 -2.275078 90)
			(size 0.2286 0.6096)
			(layers "F.Cu" "F.Mask" "F.Paste")
			(net "PVDDCR_CPU1_P1_VOS4")
		)
		(pad "2" smd rect
			(at -2.400046 -1.82499 90)
			(size 0.2286 0.6096)
			(layers "F.Cu" "F.Mask" "F.Paste")
			(net "GND")
		)
		(pad "3" smd rect
			(at -2.400046 -1.374902 90)
			(size 0.2286 0.6096)
			(layers "F.Cu" "F.Mask" "F.Paste")
			(net "PVDDCR_CPU1_P1_VCC4")
		)
		(pad "4" smd rect
			(at -2.400046 -0.925068 90)
			(size 0.2286 0.6096)
			(layers "F.Cu" "F.Mask" "F.Paste")
			(net "PVDDCR_CPU1_P1_PVCC")
		)
		(pad "5" smd rect
			(at -2.400046 -0.47498 90)
			(size 0.2286 0.6096)
			(layers "F.Cu" "F.Mask" "F.Paste")
			(net "GND")
		)
		(pad "6" smd rect
			(at -2.400046 -0.024892 90)
			(size 0.2286 0.6096)
			(layers "F.Cu" "F.Mask" "F.Paste")
			(net "NC_PVDDCR_CPU1_P1_GL1_4")
		)
		(pad "7_9-20_24" smd circle
			(at 0 1.150112 90)
			(size 0 0)
			(layers "F.Cu" "F.Mask" "F.Paste")
			(net "GND")
		)
		(pad "10_19" smd rect
			(at 0 2.899918 90)
			(size 0.6096 4.318)
			(layers "F.Cu" "F.Mask" "F.Paste")
			(net "SW_PVDDCR_CPU1_P1_SW4")
		)
		(pad "25_29" smd rect
			(at 1.549908 -1.279906 270)
			(size 2.0574 2.3114)
			(layers "F.Cu" "F.Mask" "F.Paste")
			(net "SW_P12V_AUX_PVDDCR_CPU1_P1_FLT")
		)
		(pad "30" smd rect
			(at 2.05994 -2.899918)
			(size 0.2286 0.6096)
			(layers "F.Cu" "F.Mask" "F.Paste")
			(net "SW_P12V_AUX_PVDDCR_CPU1_P1_FLT")
		)
		(pad "31" smd rect
			(at 1.610106 -2.899918)
			(size 0.2286 0.6096)
			(layers "F.Cu" "F.Mask" "F.Paste")
			(net "NC_PVDDCR_CPU1_P1_DNC4")
		)
		(pad "32" smd rect
			(at 1.160018 -2.899918)
			(size 0.2286 0.6096)
			(layers "F.Cu" "F.Mask" "F.Paste")
			(net "SW_PVDDCR_CPU1_P1_BOOTR4")
		)
		(pad "33" smd rect
			(at 0.70993 -2.899918)
			(size 0.2286 0.6096)
			(layers "F.Cu" "F.Mask" "F.Paste")
			(net "SW_PVDDCR_CPU1_P1_BOOT4")
		)
		(pad "34" smd rect
			(at 0.260096 -2.899918)
			(size 0.2286 0.6096)
			(layers "F.Cu" "F.Mask" "F.Paste")
			(net "PVDDCR_CPU1_P1_PWM4")
		)
		(pad "35" smd rect
			(at -0.189992 -2.899918)
			(size 0.2286 0.6096)
			(layers "F.Cu" "F.Mask" "F.Paste")
			(net "PVDDCR_CPU1_P1_VCC4")
		)
		(pad "36" smd rect
			(at -0.64008 -2.899918)
			(size 0.2286 0.6096)
			(layers "F.Cu" "F.Mask" "F.Paste")
			(net "PVDDCR_CPU1_P1_TEMP0")
		)
		(pad "37" smd rect
			(at -1.089914 -2.899918)
			(size 0.2286 0.6096)
			(layers "F.Cu" "F.Mask" "F.Paste")
			(net "PVDDCR_CPU1_P1_LSET4")
		)
		(pad "38" smd rect
			(at -1.540002 -2.899918)
			(size 0.2286 0.6096)
			(layers "F.Cu" "F.Mask" "F.Paste")
			(net "PVDDCR_CPU1_P1_IMON4")
		)
		(pad "39" smd rect
			(at -1.99009 -2.899918)
			(size 0.2286 0.6096)
			(layers "F.Cu" "F.Mask" "F.Paste")
			(net "PVDDCR_CPU1_P1_VCCS")
		)
		(pad "40" smd rect
			(at -0.87503 -1.27508)
			(size 1.7526 1.9558)
			(layers "F.Cu" "F.Mask" "F.Paste")
			(net "GND")
		)
		(pad "41" smd rect
			(at -1.525016 0.249936 270)
			(size 0.3048 0.4572)
			(layers "F.Cu" "F.Mask" "F.Paste")
			(net "NC_PVDDCR_CPU1_P1_GL2_4")
		)
		(zone
			(layer "F.Cu")
			(hatch none 0.5)
			(connect_pads
				(clearance 0)
			)
			(min_thickness 0.25)
			(keepout
				(tracks not_allowed)
				(vias allowed)
				(pads allowed)
				(copperpour not_allowed)
				(footprints allowed)
			)
			(placement
				(enabled no)
				(sheetname "")
			)
			(fill
				(thermal_gap 0.5)
				(thermal_bridge_width 0.5)
				(island_removal_mode 0)
			)
			(polygon
				(pts
					(xy 59.374532 -344.141552) (xy 59.374532 -344.470482) (xy 64.374776 -344.470482) (xy 64.374776 -344.136726)
					(xy 64.084454 -344.136726) (xy 64.084454 -344.176858) (xy 59.664854 -344.176858) (xy 59.664854 -344.141552)
				)
			)
		)
		(zone
			(layer "F.Cu")
			(hatch none 0.5)
			(connect_pads
				(clearance 0)
			)
			(min_thickness 0.25)
			(keepout
				(tracks not_allowed)
				(vias allowed)
				(pads allowed)
				(copperpour not_allowed)
				(footprints allowed)
			)
			(placement
				(enabled no)
				(sheetname "")
			)
			(fill
				(thermal_gap 0.5)
				(thermal_bridge_width 0.5)
				(island_removal_mode 0)
			)
			(polygon
				(pts
					(xy 61.926724 -346.967556) (xy 61.926724 -349.024956) (xy 60.072524 -349.024956) (xy 60.072524 -348.78391)
					(xy 59.830208 -348.78391) (xy 59.830208 -349.265494) (xy 63.636652 -349.265494) (xy 63.636652 -349.080582)
					(xy 62.218062 -349.080582) (xy 62.218062 -346.921582) (xy 64.374776 -346.921582) (xy 64.374776 -346.6719)
					(xy 62.22238 -346.6719)
				)
			)
		)
	)
)
